(kicad_pcb
	(version 20241229)
	(generator "pcbnew")
	(generator_version "9.0")
	(general
		(thickness 1.599998)
		(legacy_teardrops no)
	)
	(paper "A4")
	(title_block
		(title "Artix - Datacenter Secure Control Module (DC-SCM)")
		(date "2024-11-06")
		(rev "1.1.3")
		(comment 9 "footprint 4 of 544 (J2), pads 1-71 of 71")
	)
	(layers
		(0 "F.Cu" signal)
		(4 "In1.Cu" signal)
		(6 "In2.Cu" signal)
		(8 "In3.Cu" signal)
		(10 "In4.Cu" signal)
		(12 "In5.Cu" signal)
		(14 "In6.Cu" signal)
		(2 "B.Cu" signal)
		(9 "F.Adhes" user "F.Adhesive")
		(11 "B.Adhes" user "B.Adhesive")
		(13 "F.Paste" user)
		(15 "B.Paste" user)
		(5 "F.SilkS" user "F.Silkscreen")
		(7 "B.SilkS" user "B.Silkscreen")
		(1 "F.Mask" user)
		(3 "B.Mask" user)
		(17 "Dwgs.User" user "User.Drawings")
		(19 "Cmts.User" user "User.Comments")
		(21 "Eco1.User" user "User.Eco1")
		(23 "Eco2.User" user "User.Eco2")
		(25 "Edge.Cuts" user)
		(27 "Margin" user)
		(31 "F.CrtYd" user "F.Courtyard")
		(29 "B.CrtYd" user "B.Courtyard")
		(35 "F.Fab" user)
		(33 "B.Fab" user)
	)
	(footprint "antmicro-footprints:Bus_M.2_Socket_Key_M_TE_1-2199230-6"
		(layer "F.Cu")
		(at 125.999 160.975 180)
		(property "Reference" "J2"
			(at 10.499 4.475 0)
			(layer "F.SilkS")
			(effects
				(font
					(size 0.7 0.7)
					(thickness 0.15)
				)
				(justify right bottom)
			)
		)
		(property "Value" "Bus_M.2_1-2199230-6"
			(at -2 9.9 0)
			(layer "F.Fab")
			(effects
				(font
					(size 0.7 0.7)
					(thickness 0.15)
				)
				(justify right bottom)
			)
		)
		(property "Datasheet" "https://www.te.com/commerce/DocumentDelivery/DDEController?Action=srchrtrv&DocNm=2199230&DocType=Customer+Drawing&DocLang=English"
			(at 0 0 180)
			(layer "F.Fab")
			(hide yes)
			(effects
				(font
					(size 1.27 1.27)
					(thickness 0.15)
				)
			)
		)
		(property "Description" "Key M Card Edge Connector, 0, Dual Side, 67 Contacts, Surface Mount, Right Angle, Solder"
			(at 0 0 180)
			(layer "F.Fab")
			(hide yes)
			(effects
				(font
					(size 1.27 1.27)
					(thickness 0.15)
				)
			)
		)
		(property "Author" "Antmicro"
			(at 251.998 321.95 0)
			(layer "F.Fab")
			(hide yes)
			(effects
				(font
					(size 1 1)
					(thickness 0.15)
				)
			)
		)
		(property "License" "Apache-2.0"
			(at 251.998 321.95 0)
			(layer "F.Fab")
			(hide yes)
			(effects
				(font
					(size 1 1)
					(thickness 0.15)
				)
			)
		)
		(property "MPN" "1-2199230-6"
			(at 251.998 321.95 0)
			(layer "F.Fab")
			(hide yes)
			(effects
				(font
					(size 1 1)
					(thickness 0.15)
				)
			)
		)
		(property "Manufacturer" "TE Connectivity"
			(at 251.998 321.95 0)
			(layer "F.Fab")
			(hide yes)
			(effects
				(font
					(size 1 1)
					(thickness 0.15)
				)
			)
		)
		(property "VSD_Class" "M.2 Key M"
			(at 251.998 321.95 0)
			(layer "F.Fab")
			(hide yes)
			(effects
				(font
					(size 1 1)
					(thickness 0.15)
				)
			)
		)
		(sheetname "/PCIe-connector/")
		(sheetfile "pcie-conn.kicad_sch")
		(attr smd)
		(pad "" np_thru_hole circle
			(at -10 1.499 180)
			(size 1.1 1.1)
			(drill 1.1)
			(layers "*.Mask")
		)
		(pad "" np_thru_hole circle
			(at 9.997 1.499 180)
			(size 1.6 1.6)
			(drill 1.6)
			(layers "*.Mask")
		)
		(pad "1" smd rect
			(at -9.25 -3.775 180)
			(size 0.3 1.55)
			(layers "F.Cu" "F.Mask" "F.Paste")
			(net 1 "GND")
			(pinfunction "GND")
			(pintype "power_in")
		)
		(pad "2" smd rect
			(at -9.003 3.773 180)
			(size 0.3 1.55)
			(layers "F.Cu" "F.Mask" "F.Paste")
			(net 2 "VCC3V3")
			(pinfunction "3V3")
			(pintype "passive")
		)
		(pad "3" smd rect
			(at -8.753 -3.775 180)
			(size 0.3 1.55)
			(layers "F.Cu" "F.Mask" "F.Paste")
			(net 1 "GND")
			(pinfunction "GND")
			(pintype "passive")
		)
		(pad "4" smd rect
			(at -8.503 3.773 180)
			(size 0.3 1.55)
			(layers "F.Cu" "F.Mask" "F.Paste")
			(net 2 "VCC3V3")
			(pinfunction "3V3")
			(pintype "passive")
		)
		(pad "5" smd rect
			(at -8.253 -3.775 180)
			(size 0.3 1.55)
			(layers "F.Cu" "F.Mask" "F.Paste")
			(net 368 "PCIE_HPM_RX[3]_N")
			(pinfunction "PER3_N")
			(pintype "output")
		)
		(pad "6" smd rect
			(at -8.001 3.773 180)
			(size 0.3 1.55)
			(layers "F.Cu" "F.Mask" "F.Paste")
			(net 229 "unconnected-(J2-NC-Pad6)")
			(pinfunction "NC")
			(pintype "no_connect")
		)
		(pad "7" smd rect
			(at -7.752 -3.775 180)
			(size 0.3 1.55)
			(layers "F.Cu" "F.Mask" "F.Paste")
			(net 367 "PCIE_HPM_RX[3]_P")
			(pinfunction "PER3_P")
			(pintype "output")
		)
		(pad "8" smd rect
			(at -7.502 3.773 180)
			(size 0.3 1.55)
			(layers "F.Cu" "F.Mask" "F.Paste")
			(net 230 "unconnected-(J2-NC-Pad8)")
			(pinfunction "NC")
			(pintype "no_connect")
		)
		(pad "9" smd rect
			(at -7.252 -3.775 180)
			(size 0.3 1.55)
			(layers "F.Cu" "F.Mask" "F.Paste")
			(net 1 "GND")
			(pinfunction "GND")
			(pintype "passive")
		)
		(pad "10" smd rect
			(at -7.002 3.773 180)
			(size 0.3 1.55)
			(layers "F.Cu" "F.Mask" "F.Paste")
			(net 527 "/PCIe-connector/NVME_LED")
			(pinfunction "LED")
			(pintype "passive")
		)
		(pad "11" smd rect
			(at -6.752 -3.775 180)
			(size 0.3 1.55)
			(layers "F.Cu" "F.Mask" "F.Paste")
			(net 376 "/PCIe-connector/PCIE_HPM_TX3_C_N")
			(pinfunction "PET3_N")
			(pintype "input")
		)
		(pad "12" smd rect
			(at -6.502 3.773 180)
			(size 0.3 1.55)
			(layers "F.Cu" "F.Mask" "F.Paste")
			(net 2 "VCC3V3")
			(pinfunction "3V3")
			(pintype "passive")
		)
		(pad "13" smd rect
			(at -6.252 -3.775 180)
			(size 0.3 1.55)
			(layers "F.Cu" "F.Mask" "F.Paste")
			(net 374 "/PCIe-connector/PCIE_HPM_TX3_C_P")
			(pinfunction "PET3_P")
			(pintype "input")
		)
		(pad "14" smd rect
			(at -6.002 3.773 180)
			(size 0.3 1.55)
			(layers "F.Cu" "F.Mask" "F.Paste")
			(net 2 "VCC3V3")
			(pinfunction "3V3")
			(pintype "passive")
		)
		(pad "15" smd rect
			(at -5.752 -3.775 180)
			(size 0.3 1.55)
			(layers "F.Cu" "F.Mask" "F.Paste")
			(net 1 "GND")
			(pinfunction "GND")
			(pintype "passive")
		)
		(pad "16" smd rect
			(at -5.502 3.773 180)
			(size 0.3 1.55)
			(layers "F.Cu" "F.Mask" "F.Paste")
			(net 2 "VCC3V3")
			(pinfunction "3V3")
			(pintype "passive")
		)
		(pad "17" smd rect
			(at -5.252 -3.775 180)
			(size 0.3 1.55)
			(layers "F.Cu" "F.Mask" "F.Paste")
			(net 366 "PCIE_HPM_RX[2]_N")
			(pinfunction "PER2_N")
			(pintype "output")
		)
		(pad "18" smd rect
			(at -5.002 3.773 180)
			(size 0.3 1.55)
			(layers "F.Cu" "F.Mask" "F.Paste")
			(net 2 "VCC3V3")
			(pinfunction "3V3")
			(pintype "passive")
		)
		(pad "19" smd rect
			(at -4.752 -3.775 180)
			(size 0.3 1.55)
			(layers "F.Cu" "F.Mask" "F.Paste")
			(net 365 "PCIE_HPM_RX[2]_P")
			(pinfunction "PER2_P")
			(pintype "output")
		)
		(pad "20" smd rect
			(at -4.502 3.773 180)
			(size 0.3 1.55)
			(layers "F.Cu" "F.Mask" "F.Paste")
			(net 231 "unconnected-(J2-NC-Pad20)")
			(pinfunction "NC")
			(pintype "no_connect")
		)
		(pad "21" smd rect
			(at -4.252 -3.775 180)
			(size 0.3 1.55)
			(layers "F.Cu" "F.Mask" "F.Paste")
			(net 1 "GND")
			(pinfunction "GND")
			(pintype "passive")
		)
		(pad "22" smd rect
			(at -4.002 3.773 180)
			(size 0.3 1.55)
			(layers "F.Cu" "F.Mask" "F.Paste")
			(net 232 "unconnected-(J2-NC-Pad22)")
			(pinfunction "NC")
			(pintype "no_connect")
		)
		(pad "23" smd rect
			(at -3.751 -3.775 180)
			(size 0.3 1.55)
			(layers "F.Cu" "F.Mask" "F.Paste")
			(net 375 "/PCIe-connector/PCIE_HPM_TX2_C_N")
			(pinfunction "PET2_N")
			(pintype "input")
		)
		(pad "24" smd rect
			(at -3.501 3.773 180)
			(size 0.3 1.55)
			(layers "F.Cu" "F.Mask" "F.Paste")
			(net 233 "unconnected-(J2-NC-Pad24)")
			(pinfunction "NC")
			(pintype "no_connect")
		)
		(pad "25" smd rect
			(at -3.251 -3.775 180)
			(size 0.3 1.55)
			(layers "F.Cu" "F.Mask" "F.Paste")
			(net 373 "/PCIe-connector/PCIE_HPM_TX2_C_P")
			(pinfunction "PET2_P")
			(pintype "input")
		)
		(pad "26" smd rect
			(at -3.001 3.773 180)
			(size 0.3 1.55)
			(layers "F.Cu" "F.Mask" "F.Paste")
			(net 234 "unconnected-(J2-NC-Pad26)")
			(pinfunction "NC")
			(pintype "no_connect")
		)
		(pad "27" smd rect
			(at -2.751 -3.775 180)
			(size 0.3 1.55)
			(layers "F.Cu" "F.Mask" "F.Paste")
			(net 1 "GND")
			(pinfunction "GND")
			(pintype "passive")
		)
		(pad "28" smd rect
			(at -2.501 3.773 180)
			(size 0.3 1.55)
			(layers "F.Cu" "F.Mask" "F.Paste")
			(net 235 "unconnected-(J2-NC-Pad28)")
			(pinfunction "NC")
			(pintype "no_connect")
		)
		(pad "29" smd rect
			(at -2.251 -3.775 180)
			(size 0.3 1.55)
			(layers "F.Cu" "F.Mask" "F.Paste")
			(net 364 "PCIE_HPM_RX[1]_N")
			(pinfunction "PER1_N")
			(pintype "output")
		)
		(pad "30" smd rect
			(at -2.001 3.773 180)
			(size 0.3 1.55)
			(layers "F.Cu" "F.Mask" "F.Paste")
			(net 236 "unconnected-(J2-NC-Pad30)")
			(pinfunction "NC")
			(pintype "no_connect")
		)
		(pad "31" smd rect
			(at -1.752 -3.775 180)
			(size 0.3 1.55)
			(layers "F.Cu" "F.Mask" "F.Paste")
			(net 363 "PCIE_HPM_RX[1]_P")
			(pinfunction "PER1_P")
			(pintype "output")
		)
		(pad "32" smd rect
			(at -1.502 3.773 180)
			(size 0.3 1.55)
			(layers "F.Cu" "F.Mask" "F.Paste")
			(net 237 "unconnected-(J2-NC-Pad32)")
			(pinfunction "NC")
			(pintype "no_connect")
		)
		(pad "33" smd rect
			(at -1.252 -3.775 180)
			(size 0.3 1.55)
			(layers "F.Cu" "F.Mask" "F.Paste")
			(net 1 "GND")
			(pinfunction "GND")
			(pintype "passive")
		)
		(pad "34" smd rect
			(at -1.002 3.773 180)
			(size 0.3 1.55)
			(layers "F.Cu" "F.Mask" "F.Paste")
			(net 238 "unconnected-(J2-NC-Pad34)")
			(pinfunction "NC")
			(pintype "no_connect")
		)
		(pad "35" smd rect
			(at -0.751 -3.775 180)
			(size 0.3 1.55)
			(layers "F.Cu" "F.Mask" "F.Paste")
			(net 372 "/PCIe-connector/PCIE_HPM_TX1_C_N")
			(pinfunction "PET1_N")
			(pintype "input")
		)
		(pad "36" smd rect
			(at -0.501 3.773 180)
			(size 0.3 1.55)
			(layers "F.Cu" "F.Mask" "F.Paste")
			(net 239 "unconnected-(J2-NC-Pad36)")
			(pinfunction "NC")
			(pintype "no_connect")
		)
		(pad "37" smd rect
			(at -0.251 -3.775 180)
			(size 0.3 1.55)
			(layers "F.Cu" "F.Mask" "F.Paste")
			(net 370 "/PCIe-connector/PCIE_HPM_TX1_C_P")
			(pinfunction "PET1_P")
			(pintype "input")
		)
		(pad "38" smd rect
			(at -0.001 3.773 180)
			(size 0.3 1.55)
			(layers "F.Cu" "F.Mask" "F.Paste")
			(net 261 "unconnected-(J2-NC-Pad38)")
			(pinfunction "NC")
			(pintype "no_connect")
		)
		(pad "39" smd rect
			(at 0.248 -3.775 180)
			(size 0.3 1.55)
			(layers "F.Cu" "F.Mask" "F.Paste")
			(net 1 "GND")
			(pinfunction "GND")
			(pintype "passive")
		)
		(pad "40" smd rect
			(at 0.498 3.773 180)
			(size 0.3 1.55)
			(layers "F.Cu" "F.Mask" "F.Paste")
			(net 262 "unconnected-(J2-SMB_CLK-Pad40)")
			(pinfunction "SMB_CLK")
			(pintype "input+no_connect")
		)
		(pad "41" smd rect
			(at 0.748 -3.775 180)
			(size 0.3 1.55)
			(layers "F.Cu" "F.Mask" "F.Paste")
			(net 362 "PCIE_HPM_RX[0]_N")
			(pinfunction "PER0_N")
			(pintype "output")
		)
		(pad "42" smd rect
			(at 0.998 3.773 180)
			(size 0.3 1.55)
			(layers "F.Cu" "F.Mask" "F.Paste")
			(net 263 "unconnected-(J2-SMB_DATA-Pad42)")
			(pinfunction "SMB_DATA")
			(pintype "bidirectional+no_connect")
		)
		(pad "43" smd rect
			(at 1.249 -3.775 180)
			(size 0.3 1.55)
			(layers "F.Cu" "F.Mask" "F.Paste")
			(net 361 "PCIE_HPM_RX[0]_P")
			(pinfunction "PER0_P")
			(pintype "output")
		)
		(pad "44" smd rect
			(at 1.499 3.773 180)
			(size 0.3 1.55)
			(layers "F.Cu" "F.Mask" "F.Paste")
			(net 264 "Net-(J2-ALERT)")
			(pinfunction "ALERT")
			(pintype "output")
		)
		(pad "45" smd rect
			(at 1.749 -3.775 180)
			(size 0.3 1.55)
			(layers "F.Cu" "F.Mask" "F.Paste")
			(net 1 "GND")
			(pinfunction "GND")
			(pintype "passive")
		)
		(pad "46" smd rect
			(at 1.999 3.773 180)
			(size 0.3 1.55)
			(layers "F.Cu" "F.Mask" "F.Paste")
			(net 265 "unconnected-(J2-NC-Pad46)")
			(pinfunction "NC")
			(pintype "no_connect")
		)
		(pad "47" smd rect
			(at 2.249 -3.775 180)
			(size 0.3 1.55)
			(layers "F.Cu" "F.Mask" "F.Paste")
			(net 371 "/PCIe-connector/PCIE_HPM_TX0_C_N")
			(pinfunction "PET0_N")
			(pintype "input")
		)
		(pad "48" smd rect
			(at 2.499 3.773 180)
			(size 0.3 1.55)
			(layers "F.Cu" "F.Mask" "F.Paste")
			(net 266 "unconnected-(J2-NC-Pad48)")
			(pinfunction "NC")
			(pintype "no_connect")
		)
		(pad "49" smd rect
			(at 2.749 -3.775 180)
			(size 0.3 1.55)
			(layers "F.Cu" "F.Mask" "F.Paste")
			(net 369 "/PCIe-connector/PCIE_HPM_TX0_C_P")
			(pinfunction "PET0_P")
			(pintype "input")
		)
		(pad "50" smd rect
			(at 2.999 3.773 180)
			(size 0.3 1.55)
			(layers "F.Cu" "F.Mask" "F.Paste")
			(net 118 "PRSNT1_N")
			(pinfunction "~{PERST}")
			(pintype "input")
		)
		(pad "51" smd rect
			(at 3.249 -3.775 180)
			(size 0.3 1.55)
			(layers "F.Cu" "F.Mask" "F.Paste")
			(net 1 "GND")
			(pinfunction "GND")
			(pintype "passive")
		)
		(pad "52" smd rect
			(at 3.499 3.773 180)
			(size 0.3 1.55)
			(layers "F.Cu" "F.Mask" "F.Paste")
			(net 269 "Net-(J2-~{CLKREQ})")
			(pinfunction "~{CLKREQ}")
			(pintype "output")
		)
		(pad "53" smd rect
			(at 3.749 -3.775 180)
			(size 0.3 1.55)
			(layers "F.Cu" "F.Mask" "F.Paste")
			(net 360 "PCIE_HPM_CLK_N")
			(pinfunction "REFCLK_N")
			(pintype "input")
		)
		(pad "54" smd rect
			(at 3.999 3.773 180)
			(size 0.3 1.55)
			(layers "F.Cu" "F.Mask" "F.Paste")
			(net 270 "Net-(J2-~{PEWAKE})")
			(pinfunction "~{PEWAKE}")
			(pintype "input")
		)
		(pad "55" smd rect
			(at 4.248 -3.775 180)
			(size 0.3 1.55)
			(layers "F.Cu" "F.Mask" "F.Paste")
			(net 359 "PCIE_HPM_CLK_P")
			(pinfunction "REFCLK_P")
			(pintype "input")
		)
		(pad "56" smd rect
			(at 4.498 3.773 180)
			(size 0.3 1.55)
			(layers "F.Cu" "F.Mask" "F.Paste")
			(net 271 "unconnected-(J2-NC-Pad56)")
			(pinfunction "NC")
			(pintype "no_connect")
		)
		(pad "57" smd rect
			(at 4.748 -3.775 180)
			(size 0.3 1.55)
			(layers "F.Cu" "F.Mask" "F.Paste")
			(net 1 "GND")
			(pinfunction "GND")
			(pintype "passive")
		)
		(pad "58" smd rect
			(at 4.998 3.773 180)
			(size 0.3 1.55)
			(layers "F.Cu" "F.Mask" "F.Paste")
			(net 272 "unconnected-(J2-NC-Pad58)")
			(pinfunction "NC")
			(pintype "no_connect")
		)
		(pad "67" smd rect
			(at 7.248 -3.775 180)
			(size 0.3 1.55)
			(layers "F.Cu" "F.Mask" "F.Paste")
			(net 273 "unconnected-(J2-NC-Pad67)")
			(pinfunction "NC")
			(pintype "no_connect")
		)
		(pad "68" smd rect
			(at 7.498 3.773 180)
			(size 0.3 1.55)
			(layers "F.Cu" "F.Mask" "F.Paste")
			(net 278 "unconnected-(J2-SUSCLK-Pad68)")
			(pinfunction "SUSCLK")
			(pintype "input+no_connect")
		)
		(pad "69" smd rect
			(at 7.748 -3.775 180)
			(size 0.3 1.55)
			(layers "F.Cu" "F.Mask" "F.Paste")
			(net 280 "unconnected-(J2-NC-Pad69)")
			(pinfunction "NC")
			(pintype "no_connect")
		)
		(pad "70" smd rect
			(at 7.998 3.773 180)
			(size 0.3 1.55)
			(layers "F.Cu" "F.Mask" "F.Paste")
			(net 2 "VCC3V3")
			(pinfunction "3V3")
			(pintype "passive")
		)
		(pad "71" smd rect
			(at 8.247 -3.775 180)
			(size 0.3 1.55)
			(layers "F.Cu" "F.Mask" "F.Paste")
			(net 1 "GND")
			(pinfunction "GND")
			(pintype "passive")
		)
		(pad "72" smd rect
			(at 8.497 3.773 180)
			(size 0.3 1.55)
			(layers "F.Cu" "F.Mask" "F.Paste")
			(net 2 "VCC3V3")
			(pinfunction "3V3")
			(pintype "passive")
		)
		(pad "73" smd rect
			(at 8.747 -3.775 180)
			(size 0.3 1.55)
			(layers "F.Cu" "F.Mask" "F.Paste")
			(net 1 "GND")
			(pinfunction "GND")
			(pintype "passive")
		)
		(pad "74" smd rect
			(at 8.997 3.773 180)
			(size 0.3 1.55)
			(layers "F.Cu" "F.Mask" "F.Paste")
			(net 2 "VCC3V3")
			(pinfunction "3V3")
			(pintype "passive")
		)
		(pad "75" smd rect
			(at 9.247 -3.775 180)
			(size 0.3 1.55)
			(layers "F.Cu" "F.Mask" "F.Paste")
			(net 1 "GND")
			(pinfunction "GND")
			(pintype "passive")
		)
		(pad "MP1" smd rect
			(at -10.352 -3 180)
			(size 1.2 2.75)
			(layers "F.Cu" "F.Mask" "F.Paste")
			(net 1 "GND")
			(pinfunction "MP")
			(pintype "passive")
		)
		(pad "MP2" smd rect
			(at 10.349 -3 180)
			(size 1.2 2.75)
			(layers "F.Cu" "F.Mask" "F.Paste")
			(net 1 "GND")
			(pinfunction "MP")
			(pintype "passive")
		)
	)
)
